# BASEBOARD_FAB2 (Tioga Pass) — schematic netlist excerpt (pin names and nets, part order shuffled) for the footprints in the layout excerpt that follows; sources: Cadence DE-HDL packaged netlist, KiCad conversion of Wiwynn_Tioga_Pass_MB.brd

R1T38  RES  0.0 5% EMPTY  pkg 0402  page 93 : A = FM_CPU1_PROCHOT_LVT3_N ; B = FM_CPU1_PROCHOT_PCH_N
C1B14  CAPP  470UF 16V 20% ALUM  pkg 4040LF  page 195 : A = P12V_STBY ; B = GND

(kicad_pcb
	(version 20260206)
	(generator "pcbnew")
	(generator_version "10.0")
	(general
		(thickness 1.6)
		(legacy_teardrops no)
	)
	(paper "A4")
	(title_block
		(title "Wiwynn_Tioga_Pass_MB.brd")
		(comment 1 "Tioga Pass / footprints 998-999 of 4770")
	)
	(layers
		(0 "F.Cu" signal "TOP")
		(4 "In1.Cu" signal "L2GND")
		(6 "In2.Cu" signal "L3")
		(8 "In3.Cu" signal "L4GND")
		(10 "In4.Cu" signal "L5")
		(12 "In5.Cu" signal "L6GND")
		(14 "In6.Cu" signal "L7VCC")
		(16 "In7.Cu" signal "L8VCC")
		(18 "In8.Cu" signal "L9GND")
		(20 "In9.Cu" signal "L10")
		(22 "In10.Cu" signal "L11GND")
		(24 "In11.Cu" signal "L12")
		(26 "In12.Cu" signal "L13GND")
		(2 "B.Cu" signal "BOTTOM")
		(9 "F.Adhes" user "F.Adhesive")
		(11 "B.Adhes" user "B.Adhesive")
		(13 "F.Paste" user "Package Geometry/Pastemask Top")
		(15 "B.Paste" user "Package Geometry/Pastemask Bottom")
		(5 "F.SilkS" user "Ref Des/Silkscreen Top")
		(7 "B.SilkS" user "Ref Des/Silkscreen Bottom")
		(1 "F.Mask" user "Board Geometry/Soldermask Top")
		(3 "B.Mask" user "Board Geometry/Soldermask Bottom")
		(17 "Dwgs.User" user "User.Drawings")
		(19 "Cmts.User" user "User.Comments")
		(21 "Eco1.User" user "User.Eco1")
		(23 "Eco2.User" user "User.Eco2")
		(25 "Edge.Cuts" user "Board Geometry/Outline")
		(27 "Margin" user)
		(31 "F.CrtYd" user "Package Geometry/Place Bound Top")
		(29 "B.CrtYd" user "Package Geometry/Place Bound Bottom")
		(35 "F.Fab" user "Ref Des/Assembly Top")
		(33 "B.Fab" user "Ref Des/Assembly Bottom")
	)
	(footprint ""
		(layer "F.Cu")
		(at 402.615146 -41.792652 90)
		(property "Reference" "R1T38"
			(at 0 0 90)
			(layer "F.SilkS")
			(hide yes)
			(effects
				(font
					(size 1.27 1.27)
				)
			)
		)
		(property "Value" ""
			(at 0 0 90)
			(layer "F.Fab")
			(effects
				(font
					(size 1.27 1.27)
				)
			)
		)
		(duplicate_pad_numbers_are_jumpers no)
		(fp_poly
			(pts
				(xy -0.2794 -0.1016) (xy 0.2794 -0.1016) (xy 0.2794 0.9906) (xy -0.2794 0.9906)
			)
			(stroke
				(width 0)
				(type default)
			)
			(fill no)
			(layer "F.CrtYd")
		)
		(fp_line
			(start 0.2794 -0.1016)
			(end -0.2794 -0.1016)
			(stroke
				(width 0.1)
				(type default)
			)
			(layer "F.Fab")
		)
		(fp_line
			(start -0.2794 -0.1016)
			(end -0.2794 0.9906)
			(stroke
				(width 0.1)
				(type default)
			)
			(layer "F.Fab")
		)
		(fp_line
			(start 0.2794 0.9906)
			(end 0.2794 -0.1016)
			(stroke
				(width 0.1)
				(type default)
			)
			(layer "F.Fab")
		)
		(fp_line
			(start -0.2794 0.9906)
			(end 0.2794 0.9906)
			(stroke
				(width 0.1)
				(type default)
			)
			(layer "F.Fab")
		)
		(pad "1" smd rect
			(at 0 0 90)
			(size 0.508 0.508)
			(layers "F.Cu" "F.Mask" "F.Paste")
			(net "FM_CPU1_PROCHOT_LVT3_N")
		)
		(pad "2" smd rect
			(at 0 0.889 90)
			(size 0.508 0.508)
			(layers "F.Cu" "F.Mask" "F.Paste")
			(net "FM_CPU1_PROCHOT_PCH_N")
		)
		(zone
			(layer "F.Cu")
			(hatch none 0.5)
			(connect_pads
				(clearance 0)
			)
			(min_thickness 0.25)
			(keepout
				(tracks allowed)
				(vias not_allowed)
				(pads allowed)
				(copperpour not_allowed)
				(footprints allowed)
			)
			(placement
				(enabled no)
				(sheetname "")
			)
			(fill
				(thermal_gap 0.5)
				(thermal_bridge_width 0.5)
				(island_removal_mode 0)
			)
			(polygon
				(pts
					(xy 402.869146 -41.538652) (xy 402.869146 -42.046652) (xy 403.250146 -42.046652) (xy 403.250146 -41.538652)
				)
			)
		)
		(zone
			(layer "F.Cu")
			(hatch none 0.5)
			(connect_pads
				(clearance 0)
			)
			(min_thickness 0.25)
			(keepout
				(tracks not_allowed)
				(vias allowed)
				(pads allowed)
				(copperpour not_allowed)
				(footprints allowed)
			)
			(placement
				(enabled no)
				(sheetname "")
			)
			(fill
				(thermal_gap 0.5)
				(thermal_bridge_width 0.5)
				(island_removal_mode 0)
			)
			(polygon
				(pts
					(xy 403.250146 -41.538652) (xy 403.250146 -42.046652) (xy 402.869146 -42.046652) (xy 402.869146 -41.538652)
				)
			)
		)
	)
	(footprint ""
		(layer "F.Cu")
		(at 35.028378 -121.59361)
		(property "Reference" "C1B14"
			(at -6.204966 4.045458 270)
			(unlocked yes)
			(layer "F.SilkS")
			(effects
				(font
					(size 0.7874 0.5842)
					(thickness 0.1524)
				)
			)
		)
		(property "Value" ""
			(at 0 0 0)
			(layer "F.Fab")
			(effects
				(font
					(size 1.27 1.27)
				)
			)
		)
		(duplicate_pad_numbers_are_jumpers no)
		(fp_line
			(start -5.1435 -0.127)
			(end -4.3815 -1.016)
			(stroke
				(width 0.1524)
				(type default)
			)
			(layer "F.SilkS")
		)
		(fp_line
			(start -5.1435 9.271)
			(end -5.1435 -0.127)
			(stroke
				(width 0.1524)
				(type default)
			)
			(layer "F.SilkS")
		)
		(fp_line
			(start -4.3815 -1.016)
			(end -1.8415 -1.016)
			(stroke
				(width 0.1524)
				(type default)
			)
			(layer "F.SilkS")
		)
		(fp_line
			(start -1.8415 -2.0955)
			(end -1.8415 2.0955)
			(stroke
				(width 0.1524)
				(type default)
			)
			(layer "F.SilkS")
		)
		(fp_line
			(start -1.8415 2.0955)
			(end -1.4097 2.0955)
			(stroke
				(width 0.1524)
				(type default)
			)
			(layer "F.SilkS")
		)
		(fp_line
			(start -1.4097 -2.0955)
			(end -1.8415 -2.0955)
			(stroke
				(width 0.1524)
				(type default)
			)
			(layer "F.SilkS")
		)
		(fp_line
			(start -1.4097 9.271)
			(end -5.1435 9.271)
			(stroke
				(width 0.1524)
				(type default)
			)
			(layer "F.SilkS")
		)
		(fp_line
			(start 1.4097 -2.0955)
			(end 1.8415 -2.0955)
			(stroke
				(width 0.1524)
				(type default)
			)
			(layer "F.SilkS")
		)
		(fp_line
			(start 1.8415 -2.0955)
			(end 1.8415 2.0955)
			(stroke
				(width 0.1524)
				(type default)
			)
			(layer "F.SilkS")
		)
		(fp_line
			(start 1.8415 -1.016)
			(end 4.3815 -1.016)
			(stroke
				(width 0.1524)
				(type default)
			)
			(layer "F.SilkS")
		)
		(fp_line
			(start 1.8415 2.0955)
			(end 1.4097 2.0955)
			(stroke
				(width 0.1524)
				(type default)
			)
			(layer "F.SilkS")
		)
		(fp_line
			(start 4.3815 -1.016)
			(end 5.1435 -0.127)
			(stroke
				(width 0.1524)
				(type default)
			)
			(layer "F.SilkS")
		)
		(fp_line
			(start 5.1435 -0.127)
			(end 5.1435 9.271)
			(stroke
				(width 0.1524)
				(type default)
			)
			(layer "F.SilkS")
		)
		(fp_line
			(start 5.1435 9.271)
			(end 1.4097 9.271)
			(stroke
				(width 0.1524)
				(type default)
			)
			(layer "F.SilkS")
		)
		(fp_poly
			(pts
				(xy -5.14604 -0.12954) (xy -4.38404 -1.01346) (xy 4.37896 -1.016) (xy 5.1435 -0.12954) (xy 5.14096 9.271)
				(xy -5.14604 9.27354)
			)
			(stroke
				(width 0)
				(type default)
			)
			(fill no)
			(layer "F.CrtYd")
		)
		(fp_line
			(start -5.1435 -0.127)
			(end -4.3815 -1.016)
			(stroke
				(width 0.1)
				(type default)
			)
			(layer "F.Fab")
		)
		(fp_line
			(start -5.1435 9.271)
			(end -5.1435 -0.127)
			(stroke
				(width 0.1)
				(type default)
			)
			(layer "F.Fab")
		)
		(fp_line
			(start -4.3815 -1.016)
			(end 4.3815 -1.016)
			(stroke
				(width 0.1)
				(type default)
			)
			(layer "F.Fab")
		)
		(fp_line
			(start 4.3815 -1.016)
			(end 5.1435 -0.127)
			(stroke
				(width 0.1)
				(type default)
			)
			(layer "F.Fab")
		)
		(fp_line
			(start 5.1435 -0.127)
			(end 5.1435 9.271)
			(stroke
				(width 0.1)
				(type default)
			)
			(layer "F.Fab")
		)
		(fp_line
			(start 5.1435 9.271)
			(end -5.1435 9.271)
			(stroke
				(width 0.1)
				(type default)
			)
			(layer "F.Fab")
		)
		(fp_circle
			(center 0 4.1275)
			(end 4.9911 4.1275)
			(stroke
				(width 0.1)
				(type default)
			)
			(fill no)
			(layer "F.Fab")
		)
		(pad "1" smd rect
			(at 0 0)
			(size 1.905 4.191)
			(layers "F.Cu" "F.Mask" "F.Paste")
			(net "P12V_STBY")
		)
		(pad "2" smd rect
			(at 0 8.255)
			(size 1.905 4.191)
			(layers "F.Cu" "F.Mask" "F.Paste")
			(net "GND")
		)
		(zone
			(layer "F.Cu")
			(hatch none 0.5)
			(connect_pads
				(clearance 0)
			)
			(min_thickness 0.25)
			(keepout
				(tracks allowed)
				(vias not_allowed)
				(pads allowed)
				(copperpour not_allowed)
				(footprints allowed)
			)
			(placement
				(enabled no)
				(sheetname "")
			)
			(fill
				(thermal_gap 0.5)
				(thermal_bridge_width 0.5)
				(island_removal_mode 0)
			)
			(polygon
				(pts
					(xy 29.884878 -112.32261) (xy 40.171878 -112.32261) (xy 40.171878 -121.72061) (xy 39.409878 -122.60961)
					(xy 30.646878 -122.60961) (xy 29.884878 -121.72061)
				)
			)
		)
	)
)
